# BASEBOARD_FAB2 (Tioga Pass) — schematic netlist excerpt (pin names and nets, part order shuffled) for the footprints in the layout excerpt that follows; sources: Cadence DE-HDL packaged netlist, KiCad conversion of Wiwynn_Tioga_Pass_MB.brd

C1M25  CAP_A  1.0UF 6.3V 10% X6S  pkg 0402V  page 186 : A = P3V3_STBY ; B = GND
C5L5  CAP  100UF 4V 20% X5R  pkg 0805  page 222 : A = PVTT_DEF ; B = GND
C2T29  CAP_A  0.1UF 16V 10% X7R  pkg 0402V  page 185 : A = P3V3 ; B = GND

(kicad_pcb
	(version 20260206)
	(generator "pcbnew")
	(generator_version "10.0")
	(general
		(thickness 1.6)
		(legacy_teardrops no)
	)
	(paper "A4")
	(title_block
		(title "Wiwynn_Tioga_Pass_MB.brd")
		(comment 1 "Tioga Pass / footprints 3121-3123 of 4770")
	)
	(layers
		(0 "F.Cu" signal "TOP")
		(4 "In1.Cu" signal "L2GND")
		(6 "In2.Cu" signal "L3")
		(8 "In3.Cu" signal "L4GND")
		(10 "In4.Cu" signal "L5")
		(12 "In5.Cu" signal "L6GND")
		(14 "In6.Cu" signal "L7VCC")
		(16 "In7.Cu" signal "L8VCC")
		(18 "In8.Cu" signal "L9GND")
		(20 "In9.Cu" signal "L10")
		(22 "In10.Cu" signal "L11GND")
		(24 "In11.Cu" signal "L12")
		(26 "In12.Cu" signal "L13GND")
		(2 "B.Cu" signal "BOTTOM")
		(9 "F.Adhes" user "F.Adhesive")
		(11 "B.Adhes" user "B.Adhesive")
		(13 "F.Paste" user "Package Geometry/Pastemask Top")
		(15 "B.Paste" user "Package Geometry/Pastemask Bottom")
		(5 "F.SilkS" user "Ref Des/Silkscreen Top")
		(7 "B.SilkS" user "Ref Des/Silkscreen Bottom")
		(1 "F.Mask" user "Board Geometry/Soldermask Top")
		(3 "B.Mask" user "Board Geometry/Soldermask Bottom")
		(17 "Dwgs.User" user "User.Drawings")
		(19 "Cmts.User" user "User.Comments")
		(21 "Eco1.User" user "User.Eco1")
		(23 "Eco2.User" user "User.Eco2")
		(25 "Edge.Cuts" user "Board Geometry/Outline")
		(27 "Margin" user)
		(31 "F.CrtYd" user "Package Geometry/Place Bound Top")
		(29 "B.CrtYd" user "Package Geometry/Place Bound Bottom")
		(35 "F.Fab" user "Ref Des/Assembly Top")
		(33 "B.Fab" user "Ref Des/Assembly Bottom")
	)
	(footprint ""
		(layer "B.Cu")
		(at 483.616 -113.06302)
		(property "Reference" "C1M25"
			(at 0 0 0)
			(layer "B.SilkS")
			(hide yes)
			(effects
				(font
					(size 1.27 1.27)
				)
				(justify mirror)
			)
		)
		(property "Value" ""
			(at 0 0 0)
			(layer "B.Fab")
			(effects
				(font
					(size 1.27 1.27)
				)
				(justify mirror)
			)
		)
		(duplicate_pad_numbers_are_jumpers no)
		(fp_rect
			(start -0.3048 0.9906)
			(end 0.3048 -0.1016)
			(stroke
				(width 0)
				(type default)
			)
			(fill no)
			(layer "B.CrtYd")
		)
		(fp_line
			(start -0.3048 -0.1016)
			(end 0.3048 -0.1016)
			(stroke
				(width 0.1)
				(type default)
			)
			(layer "B.Fab")
		)
		(fp_line
			(start -0.3048 0.9906)
			(end -0.3048 -0.1016)
			(stroke
				(width 0.1)
				(type default)
			)
			(layer "B.Fab")
		)
		(fp_line
			(start 0.3048 -0.1016)
			(end 0.3048 0.9906)
			(stroke
				(width 0.1)
				(type default)
			)
			(layer "B.Fab")
		)
		(fp_line
			(start 0.3048 0.9906)
			(end -0.3048 0.9906)
			(stroke
				(width 0.1)
				(type default)
			)
			(layer "B.Fab")
		)
		(pad "1" smd rect
			(at 0 0 180)
			(size 0.508 0.508)
			(layers "B.Cu" "B.Mask" "B.Paste")
			(net "P3V3_STBY")
		)
		(pad "2" smd rect
			(at 0 0.889 180)
			(size 0.508 0.508)
			(layers "B.Cu" "B.Mask" "B.Paste")
			(net "GND")
		)
		(zone
			(layer "B.Cu")
			(hatch none 0.5)
			(connect_pads
				(clearance 0)
			)
			(min_thickness 0.25)
			(keepout
				(tracks not_allowed)
				(vias allowed)
				(pads allowed)
				(copperpour not_allowed)
				(footprints allowed)
			)
			(placement
				(enabled no)
				(sheetname "")
			)
			(fill
				(thermal_gap 0.5)
				(thermal_bridge_width 0.5)
				(island_removal_mode 0)
			)
			(polygon
				(pts
					(xy 483.362 -112.42802) (xy 483.87 -112.42802) (xy 483.87 -112.80902) (xy 483.362 -112.80902)
				)
			)
		)
		(zone
			(layer "B.Cu")
			(hatch none 0.5)
			(connect_pads
				(clearance 0)
			)
			(min_thickness 0.25)
			(keepout
				(tracks allowed)
				(vias not_allowed)
				(pads allowed)
				(copperpour not_allowed)
				(footprints allowed)
			)
			(placement
				(enabled no)
				(sheetname "")
			)
			(fill
				(thermal_gap 0.5)
				(thermal_bridge_width 0.5)
				(island_removal_mode 0)
			)
			(polygon
				(pts
					(xy 483.362 -112.42802) (xy 483.87 -112.42802) (xy 483.87 -112.80902) (xy 483.362 -112.80902)
				)
			)
		)
	)
	(footprint ""
		(layer "B.Cu")
		(at 261.7978 -157.0228 -90)
		(property "Reference" "C5L5"
			(at -1.47828 0.78994 0)
			(unlocked yes)
			(layer "B.SilkS")
			(effects
				(font
					(size 0.4064 0.254)
					(thickness 0.1524)
				)
				(justify mirror)
			)
		)
		(property "Value" ""
			(at 0 0 90)
			(layer "B.Fab")
			(effects
				(font
					(size 1.27 1.27)
				)
				(justify mirror)
			)
		)
		(duplicate_pad_numbers_are_jumpers no)
		(fp_poly
			(pts
				(xy 0.7239 -0.2159) (xy -0.7239 -0.2159) (xy -0.7239 1.9939) (xy 0.7239 1.9939)
			)
			(stroke
				(width 0)
				(type default)
			)
			(fill no)
			(layer "B.CrtYd")
		)
		(fp_line
			(start -0.7239 1.9939)
			(end -0.7239 -0.2159)
			(stroke
				(width 0.1)
				(type default)
			)
			(layer "B.Fab")
		)
		(fp_line
			(start 0.7239 1.9939)
			(end -0.7239 1.9939)
			(stroke
				(width 0.1)
				(type default)
			)
			(layer "B.Fab")
		)
		(fp_line
			(start -0.7239 -0.2159)
			(end 0.7239 -0.2159)
			(stroke
				(width 0.1)
				(type default)
			)
			(layer "B.Fab")
		)
		(fp_line
			(start 0.7239 -0.2159)
			(end 0.7239 1.9939)
			(stroke
				(width 0.1)
				(type default)
			)
			(layer "B.Fab")
		)
		(pad "1" smd rect
			(at 0 0 90)
			(size 1.27 1.016)
			(layers "B.Cu" "B.Mask" "B.Paste")
			(net "PVTT_DEF")
		)
		(pad "2" smd rect
			(at 0 1.778 90)
			(size 1.27 1.016)
			(layers "B.Cu" "B.Mask" "B.Paste")
			(net "GND")
		)
		(zone
			(layer "B.Cu")
			(hatch none 0.5)
			(connect_pads
				(clearance 0)
			)
			(min_thickness 0.25)
			(keepout
				(tracks not_allowed)
				(vias allowed)
				(pads allowed)
				(copperpour not_allowed)
				(footprints allowed)
			)
			(placement
				(enabled no)
				(sheetname "")
			)
			(fill
				(thermal_gap 0.5)
				(thermal_bridge_width 0.5)
				(island_removal_mode 0)
			)
			(polygon
				(pts
					(xy 261.2898 -156.3878) (xy 261.2898 -157.6578) (xy 260.5278 -157.6578) (xy 260.5278 -156.3878)
				)
			)
		)
	)
	(footprint ""
		(layer "B.Cu")
		(at 390.635744 -21.679916 -90)
		(property "Reference" "C2T29"
			(at 0 0 90)
			(layer "B.SilkS")
			(hide yes)
			(effects
				(font
					(size 1.27 1.27)
				)
				(justify mirror)
			)
		)
		(property "Value" ""
			(at 0 0 90)
			(layer "B.Fab")
			(effects
				(font
					(size 1.27 1.27)
				)
				(justify mirror)
			)
		)
		(duplicate_pad_numbers_are_jumpers no)
		(fp_poly
			(pts
				(xy -0.3048 -0.1016) (xy -0.3048 0.9906) (xy 0.3048 0.9906) (xy 0.3048 -0.1016)
			)
			(stroke
				(width 0)
				(type default)
			)
			(fill no)
			(layer "B.CrtYd")
		)
		(fp_line
			(start -0.3048 0.9906)
			(end -0.3048 -0.1016)
			(stroke
				(width 0.1)
				(type default)
			)
			(layer "B.Fab")
		)
		(fp_line
			(start 0.3048 0.9906)
			(end -0.3048 0.9906)
			(stroke
				(width 0.1)
				(type default)
			)
			(layer "B.Fab")
		)
		(fp_line
			(start -0.3048 -0.1016)
			(end 0.3048 -0.1016)
			(stroke
				(width 0.1)
				(type default)
			)
			(layer "B.Fab")
		)
		(fp_line
			(start 0.3048 -0.1016)
			(end 0.3048 0.9906)
			(stroke
				(width 0.1)
				(type default)
			)
			(layer "B.Fab")
		)
		(pad "1" smd rect
			(at 0 0 90)
			(size 0.508 0.508)
			(layers "B.Cu" "B.Mask" "B.Paste")
			(net "P3V3")
		)
		(pad "2" smd rect
			(at 0 0.889 90)
			(size 0.508 0.508)
			(layers "B.Cu" "B.Mask" "B.Paste")
			(net "GND")
		)
		(zone
			(layer "B.Cu")
			(hatch none 0.5)
			(connect_pads
				(clearance 0)
			)
			(min_thickness 0.25)
			(keepout
				(tracks not_allowed)
				(vias allowed)
				(pads allowed)
				(copperpour not_allowed)
				(footprints allowed)
			)
			(placement
				(enabled no)
				(sheetname "")
			)
			(fill
				(thermal_gap 0.5)
				(thermal_bridge_width 0.5)
				(island_removal_mode 0)
			)
			(polygon
				(pts
					(xy 390.000744 -21.425916) (xy 390.000744 -21.933916) (xy 390.381744 -21.933916) (xy 390.381744 -21.425916)
				)
			)
		)
		(zone
			(layer "B.Cu")
			(hatch none 0.5)
			(connect_pads
				(clearance 0)
			)
			(min_thickness 0.25)
			(keepout
				(tracks allowed)
				(vias not_allowed)
				(pads allowed)
				(copperpour not_allowed)
				(footprints allowed)
			)
			(placement
				(enabled no)
				(sheetname "")
			)
			(fill
				(thermal_gap 0.5)
				(thermal_bridge_width 0.5)
				(island_removal_mode 0)
			)
			(polygon
				(pts
					(xy 390.381744 -21.425916) (xy 390.381744 -21.933916) (xy 390.000744 -21.933916) (xy 390.000744 -21.425916)
				)
			)
		)
	)
)
